# T6G (Grand Teton) — schematic netlist excerpt (pin names and nets, part order shuffled) for the footprints in the layout excerpt that follows; sources: Cadence DE-HDL packaged netlist, KiCad conversion of 04192023_DAF0TMB3IC0_F0TG_MB_C_brd_V02_OCP.brd

PR8010  Q_RES  0 5% CHIP  pkg 0402LF  page 210 : A = SVID_PVDDCR_CPU0_P1_SVD_R ; B = SVID_PVDDCR_CPU0_P1_SVD_R1
C531  Q_CAP  10UF 25V 10% X6S  pkg C0805  page 104 : A = P12V_MEM_CPU1 ; B = GND
C114  Q_CAP  100UF 4V 20% X6S  pkg C0805  page 323 : A = P1V8_CPU1_RT0_1A ; B = GND

(kicad_pcb
	(version 20260206)
	(generator "pcbnew")
	(generator_version "10.0")
	(general
		(thickness 1.6)
		(legacy_teardrops no)
	)
	(paper "A4")
	(title_block
		(title "04192023_DAF0TMB3IC0_F0TG_MB_C_brd_V02_OCP.brd")
		(comment 1 "Grand Teton / footprints 5579-5581 of 8354")
	)
	(layers
		(0 "F.Cu" signal "TOP")
		(4 "In1.Cu" signal "GND")
		(6 "In2.Cu" signal "IN1")
		(8 "In3.Cu" signal "GND1")
		(10 "In4.Cu" signal "IN2")
		(12 "In5.Cu" signal "GND2")
		(14 "In6.Cu" signal "IN3")
		(16 "In7.Cu" signal "GND3")
		(18 "In8.Cu" signal "VCC")
		(20 "In9.Cu" signal "VCC1")
		(22 "In10.Cu" signal "GND4")
		(24 "In11.Cu" signal "IN4")
		(26 "In12.Cu" signal "GND5")
		(28 "In13.Cu" signal "IN5")
		(30 "In14.Cu" signal "GND6")
		(32 "In15.Cu" signal "IN6")
		(34 "In16.Cu" signal "GND7")
		(2 "B.Cu" signal "BOTTOM")
		(9 "F.Adhes" user "F.Adhesive")
		(11 "B.Adhes" user "B.Adhesive")
		(13 "F.Paste" user "Package Geometry/Pastemask Top")
		(15 "B.Paste" user "Package Geometry/Pastemask Bottom")
		(5 "F.SilkS" user "Ref Des/Silkscreen Top")
		(7 "B.SilkS" user "Ref Des/Silkscreen Bottom")
		(1 "F.Mask" user "Board Geometry/Soldermask Top")
		(3 "B.Mask" user "Board Geometry/Soldermask Bottom")
		(17 "Dwgs.User" user "User.Drawings")
		(19 "Cmts.User" user "User.Comments")
		(21 "Eco1.User" user "User.Eco1")
		(23 "Eco2.User" user "User.Eco2")
		(25 "Edge.Cuts" user "Board Geometry/Outline")
		(27 "Margin" user)
		(31 "F.CrtYd" user "Package Geometry/Place Bound Top")
		(29 "B.CrtYd" user "Package Geometry/Place Bound Bottom")
		(35 "F.Fab" user "Ref Des/Assembly Top")
		(33 "B.Fab" user "Ref Des/Assembly Bottom")
	)
	(footprint ""
		(layer "B.Cu")
		(at 88.138 -146.939 180)
		(property "Reference" "PR8010"
			(at 0 0 0)
			(layer "B.SilkS")
			(hide yes)
			(effects
				(font
					(size 1.27 1.27)
				)
				(justify mirror)
			)
		)
		(property "Value" ""
			(at 0 0 0)
			(layer "B.Fab")
			(effects
				(font
					(size 1.27 1.27)
				)
				(justify mirror)
			)
		)
		(duplicate_pad_numbers_are_jumpers no)
		(fp_line
			(start 0.7874 0.4064)
			(end 0.7874 -0.4064)
			(stroke
				(width 0.1524)
				(type default)
			)
			(layer "B.SilkS")
		)
		(fp_line
			(start 0.7874 -0.4064)
			(end -0.7874 -0.4064)
			(stroke
				(width 0.1524)
				(type default)
			)
			(layer "B.SilkS")
		)
		(fp_line
			(start -0.7874 0.4064)
			(end 0.7874 0.4064)
			(stroke
				(width 0.1524)
				(type default)
			)
			(layer "B.SilkS")
		)
		(fp_line
			(start -0.7874 -0.4064)
			(end -0.7874 0.4064)
			(stroke
				(width 0.1524)
				(type default)
			)
			(layer "B.SilkS")
		)
		(fp_line
			(start 0.67945 0.3048)
			(end 0.67945 -0.305054)
			(stroke
				(width 0.1)
				(type default)
			)
			(layer "B.Fab")
		)
		(fp_line
			(start 0.67945 -0.305054)
			(end 0.12065 -0.305054)
			(stroke
				(width 0.1)
				(type default)
			)
			(layer "B.Fab")
		)
		(fp_line
			(start 0.12065 0.3048)
			(end 0.67945 0.3048)
			(stroke
				(width 0.1)
				(type default)
			)
			(layer "B.Fab")
		)
		(fp_line
			(start 0.12065 0.2794)
			(end 0.12065 0.3048)
			(stroke
				(width 0.1)
				(type default)
			)
			(layer "B.Fab")
		)
		(fp_line
			(start 0.12065 -0.2794)
			(end -0.12065 -0.2794)
			(stroke
				(width 0.1)
				(type default)
			)
			(layer "B.Fab")
		)
		(fp_line
			(start 0.12065 -0.305054)
			(end 0.12065 -0.2794)
			(stroke
				(width 0.1)
				(type default)
			)
			(layer "B.Fab")
		)
		(fp_line
			(start -0.120396 0.3048)
			(end -0.120396 0.2794)
			(stroke
				(width 0.1)
				(type default)
			)
			(layer "B.Fab")
		)
		(fp_line
			(start -0.120396 0.2794)
			(end 0.12065 0.2794)
			(stroke
				(width 0.1)
				(type default)
			)
			(layer "B.Fab")
		)
		(fp_line
			(start -0.12065 -0.2794)
			(end -0.12065 -0.3048)
			(stroke
				(width 0.1)
				(type default)
			)
			(layer "B.Fab")
		)
		(fp_line
			(start -0.12065 -0.3048)
			(end -0.67945 -0.3048)
			(stroke
				(width 0.1)
				(type default)
			)
			(layer "B.Fab")
		)
		(fp_line
			(start -0.67945 0.3048)
			(end -0.120396 0.3048)
			(stroke
				(width 0.1)
				(type default)
			)
			(layer "B.Fab")
		)
		(fp_line
			(start -0.67945 -0.3048)
			(end -0.67945 0.3048)
			(stroke
				(width 0.1)
				(type default)
			)
			(layer "B.Fab")
		)
		(pad "1" smd circle
			(at 0.40005 0)
			(size 0 0)
			(layers "B.Cu" "B.Mask" "B.Paste")
			(net "SVID_PVDDCR_CPU0_P1_SVD_R")
		)
		(pad "2" smd circle
			(at -0.40005 0)
			(size 0 0)
			(layers "B.Cu" "B.Mask" "B.Paste")
			(net "SVID_PVDDCR_CPU0_P1_SVD_R1")
		)
	)
	(footprint ""
		(layer "B.Cu")
		(at 68.916296 -387.084062 -90)
		(property "Reference" "C114"
			(at 0 0 90)
			(layer "B.SilkS")
			(hide yes)
			(effects
				(font
					(size 1.27 1.27)
				)
				(justify mirror)
			)
		)
		(property "Value" ""
			(at 0 0 90)
			(layer "B.Fab")
			(effects
				(font
					(size 1.27 1.27)
				)
				(justify mirror)
			)
		)
		(duplicate_pad_numbers_are_jumpers no)
		(fp_line
			(start -1.524 0.762)
			(end 1.524 0.762)
			(stroke
				(width 0.1524)
				(type default)
			)
			(layer "B.SilkS")
		)
		(fp_line
			(start 1.524 0.762)
			(end 1.524 -0.762)
			(stroke
				(width 0.1524)
				(type default)
			)
			(layer "B.SilkS")
		)
		(fp_line
			(start -1.524 -0.762)
			(end -1.524 0.762)
			(stroke
				(width 0.1524)
				(type default)
			)
			(layer "B.SilkS")
		)
		(fp_line
			(start 1.524 -0.762)
			(end -1.524 -0.762)
			(stroke
				(width 0.1524)
				(type default)
			)
			(layer "B.SilkS")
		)
		(fp_line
			(start -1.1049 0.724916)
			(end -1.1049 -0.724916)
			(stroke
				(width 0.1)
				(type default)
			)
			(layer "B.Fab")
		)
		(fp_line
			(start 1.1049 0.724916)
			(end -1.1049 0.724916)
			(stroke
				(width 0.1)
				(type default)
			)
			(layer "B.Fab")
		)
		(fp_line
			(start -1.1049 -0.724916)
			(end 1.1049 -0.724916)
			(stroke
				(width 0.1)
				(type default)
			)
			(layer "B.Fab")
		)
		(fp_line
			(start 1.1049 -0.724916)
			(end 1.1049 0.724916)
			(stroke
				(width 0.1)
				(type default)
			)
			(layer "B.Fab")
		)
		(pad "1" smd rect
			(at 0.889 0 270)
			(size 1.016 1.27)
			(layers "B.Cu" "B.Mask" "B.Paste")
			(net "P1V8_CPU1_RT0_1A")
		)
		(pad "2" smd rect
			(at -0.889 0 270)
			(size 1.016 1.27)
			(layers "B.Cu" "B.Mask" "B.Paste")
			(net "GND")
		)
	)
	(footprint ""
		(layer "B.Cu")
		(at 164.42817 -192.66027 180)
		(property "Reference" "C531"
			(at 0 0 0)
			(layer "B.SilkS")
			(hide yes)
			(effects
				(font
					(size 1.27 1.27)
				)
				(justify mirror)
			)
		)
		(property "Value" ""
			(at 0 0 0)
			(layer "B.Fab")
			(effects
				(font
					(size 1.27 1.27)
				)
				(justify mirror)
			)
		)
		(duplicate_pad_numbers_are_jumpers no)
		(fp_line
			(start 1.524 0.762)
			(end 1.524 -0.762)
			(stroke
				(width 0.1524)
				(type default)
			)
			(layer "B.SilkS")
		)
		(fp_line
			(start 1.524 -0.762)
			(end -1.524 -0.762)
			(stroke
				(width 0.1524)
				(type default)
			)
			(layer "B.SilkS")
		)
		(fp_line
			(start -1.524 0.762)
			(end 1.524 0.762)
			(stroke
				(width 0.1524)
				(type default)
			)
			(layer "B.SilkS")
		)
		(fp_line
			(start -1.524 -0.762)
			(end -1.524 0.762)
			(stroke
				(width 0.1524)
				(type default)
			)
			(layer "B.SilkS")
		)
		(fp_line
			(start 1.1049 0.724916)
			(end -1.1049 0.724916)
			(stroke
				(width 0.1)
				(type default)
			)
			(layer "B.Fab")
		)
		(fp_line
			(start 1.1049 -0.724916)
			(end 1.1049 0.724916)
			(stroke
				(width 0.1)
				(type default)
			)
			(layer "B.Fab")
		)
		(fp_line
			(start -1.1049 0.724916)
			(end -1.1049 -0.724916)
			(stroke
				(width 0.1)
				(type default)
			)
			(layer "B.Fab")
		)
		(fp_line
			(start -1.1049 -0.724916)
			(end 1.1049 -0.724916)
			(stroke
				(width 0.1)
				(type default)
			)
			(layer "B.Fab")
		)
		(pad "1" smd rect
			(at 0.889 0 180)
			(size 1.016 1.27)
			(layers "B.Cu" "B.Mask" "B.Paste")
			(net "P12V_MEM_CPU1")
		)
		(pad "2" smd rect
			(at -0.889 0 180)
			(size 1.016 1.27)
			(layers "B.Cu" "B.Mask" "B.Paste")
			(net "GND")
		)
	)
)
